# T6G (Grand Teton) — schematic netlist excerpt (pin names and nets, part order shuffled) for the footprints in the layout excerpt that follows; sources: Cadence DE-HDL packaged netlist, KiCad conversion of 04192023_DAF0TMB3IC0_F0TG_MB_C_brd_V02_OCP.brd

R756  Q_RES  200 1% CHIP  pkg 0201LF  page 331 : A = RT_CPU1_P1_SCAN_MODE ; B = GND
R207  Q_RES  2.2K 5% CHIP  pkg 0402LF  page 28 : A = FM_INT_CPU0_HP_UBM_N ; B = PVDD18_S5_P0
R6752  Q_RES  1K 1% CHIP  pkg 0201LF  page 184 : A = P1V8_CPU1_RT_1D ; B = SMB_RT_CPU1_P2_R_SDA

(kicad_pcb
	(version 20260206)
	(generator "pcbnew")
	(generator_version "10.0")
	(general
		(thickness 1.6)
		(legacy_teardrops no)
	)
	(paper "A4")
	(title_block
		(title "04192023_DAF0TMB3IC0_F0TG_MB_C_brd_V02_OCP.brd")
		(comment 1 "Grand Teton / footprints 5788-5790 of 8354")
	)
	(layers
		(0 "F.Cu" signal "TOP")
		(4 "In1.Cu" signal "GND")
		(6 "In2.Cu" signal "IN1")
		(8 "In3.Cu" signal "GND1")
		(10 "In4.Cu" signal "IN2")
		(12 "In5.Cu" signal "GND2")
		(14 "In6.Cu" signal "IN3")
		(16 "In7.Cu" signal "GND3")
		(18 "In8.Cu" signal "VCC")
		(20 "In9.Cu" signal "VCC1")
		(22 "In10.Cu" signal "GND4")
		(24 "In11.Cu" signal "IN4")
		(26 "In12.Cu" signal "GND5")
		(28 "In13.Cu" signal "IN5")
		(30 "In14.Cu" signal "GND6")
		(32 "In15.Cu" signal "IN6")
		(34 "In16.Cu" signal "GND7")
		(2 "B.Cu" signal "BOTTOM")
		(9 "F.Adhes" user "F.Adhesive")
		(11 "B.Adhes" user "B.Adhesive")
		(13 "F.Paste" user "Package Geometry/Pastemask Top")
		(15 "B.Paste" user "Package Geometry/Pastemask Bottom")
		(5 "F.SilkS" user "Ref Des/Silkscreen Top")
		(7 "B.SilkS" user "Ref Des/Silkscreen Bottom")
		(1 "F.Mask" user "Board Geometry/Soldermask Top")
		(3 "B.Mask" user "Board Geometry/Soldermask Bottom")
		(17 "Dwgs.User" user "User.Drawings")
		(19 "Cmts.User" user "User.Comments")
		(21 "Eco1.User" user "User.Eco1")
		(23 "Eco2.User" user "User.Eco2")
		(25 "Edge.Cuts" user "Board Geometry/Outline")
		(27 "Margin" user)
		(31 "F.CrtYd" user "Package Geometry/Place Bound Top")
		(29 "B.CrtYd" user "Package Geometry/Place Bound Bottom")
		(35 "F.Fab" user "Ref Des/Assembly Top")
		(33 "B.Fab" user "Ref Des/Assembly Bottom")
	)
	(footprint ""
		(layer "B.Cu")
		(at 343.960958 -306.828952 180)
		(property "Reference" "R207"
			(at 0 0 0)
			(layer "B.SilkS")
			(hide yes)
			(effects
				(font
					(size 1.27 1.27)
				)
				(justify mirror)
			)
		)
		(property "Value" ""
			(at 0 0 0)
			(layer "B.Fab")
			(effects
				(font
					(size 1.27 1.27)
				)
				(justify mirror)
			)
		)
		(duplicate_pad_numbers_are_jumpers no)
		(fp_line
			(start 0.7874 0.4064)
			(end 0.7874 -0.4064)
			(stroke
				(width 0.1524)
				(type default)
			)
			(layer "B.SilkS")
		)
		(fp_line
			(start 0.7874 -0.4064)
			(end -0.7874 -0.4064)
			(stroke
				(width 0.1524)
				(type default)
			)
			(layer "B.SilkS")
		)
		(fp_line
			(start -0.7874 0.4064)
			(end 0.7874 0.4064)
			(stroke
				(width 0.1524)
				(type default)
			)
			(layer "B.SilkS")
		)
		(fp_line
			(start -0.7874 -0.4064)
			(end -0.7874 0.4064)
			(stroke
				(width 0.1524)
				(type default)
			)
			(layer "B.SilkS")
		)
		(fp_line
			(start 0.67945 0.3048)
			(end 0.67945 -0.305054)
			(stroke
				(width 0.1)
				(type default)
			)
			(layer "B.Fab")
		)
		(fp_line
			(start 0.67945 -0.305054)
			(end 0.12065 -0.305054)
			(stroke
				(width 0.1)
				(type default)
			)
			(layer "B.Fab")
		)
		(fp_line
			(start 0.12065 0.3048)
			(end 0.67945 0.3048)
			(stroke
				(width 0.1)
				(type default)
			)
			(layer "B.Fab")
		)
		(fp_line
			(start 0.12065 0.2794)
			(end 0.12065 0.3048)
			(stroke
				(width 0.1)
				(type default)
			)
			(layer "B.Fab")
		)
		(fp_line
			(start 0.12065 -0.2794)
			(end -0.12065 -0.2794)
			(stroke
				(width 0.1)
				(type default)
			)
			(layer "B.Fab")
		)
		(fp_line
			(start 0.12065 -0.305054)
			(end 0.12065 -0.2794)
			(stroke
				(width 0.1)
				(type default)
			)
			(layer "B.Fab")
		)
		(fp_line
			(start -0.120396 0.3048)
			(end -0.120396 0.2794)
			(stroke
				(width 0.1)
				(type default)
			)
			(layer "B.Fab")
		)
		(fp_line
			(start -0.120396 0.2794)
			(end 0.12065 0.2794)
			(stroke
				(width 0.1)
				(type default)
			)
			(layer "B.Fab")
		)
		(fp_line
			(start -0.12065 -0.2794)
			(end -0.12065 -0.3048)
			(stroke
				(width 0.1)
				(type default)
			)
			(layer "B.Fab")
		)
		(fp_line
			(start -0.12065 -0.3048)
			(end -0.67945 -0.3048)
			(stroke
				(width 0.1)
				(type default)
			)
			(layer "B.Fab")
		)
		(fp_line
			(start -0.67945 0.3048)
			(end -0.120396 0.3048)
			(stroke
				(width 0.1)
				(type default)
			)
			(layer "B.Fab")
		)
		(fp_line
			(start -0.67945 -0.3048)
			(end -0.67945 0.3048)
			(stroke
				(width 0.1)
				(type default)
			)
			(layer "B.Fab")
		)
		(pad "1" smd circle
			(at 0.40005 0)
			(size 0 0)
			(layers "B.Cu" "B.Mask" "B.Paste")
			(net "FM_INT_CPU0_HP_UBM_N")
		)
		(pad "2" smd circle
			(at -0.40005 0)
			(size 0 0)
			(layers "B.Cu" "B.Mask" "B.Paste")
			(net "PVDD18_S5_P0")
		)
	)
	(footprint ""
		(layer "B.Cu")
		(at 75.7936 -383.7432 180)
		(property "Reference" "R756"
			(at 0 0 0)
			(layer "B.SilkS")
			(hide yes)
			(effects
				(font
					(size 1.27 1.27)
				)
				(justify mirror)
			)
		)
		(property "Value" ""
			(at 0 0 0)
			(layer "B.Fab")
			(effects
				(font
					(size 1.27 1.27)
				)
				(justify mirror)
			)
		)
		(duplicate_pad_numbers_are_jumpers no)
		(fp_line
			(start 0.32512 0.175006)
			(end 0.32512 -0.175006)
			(stroke
				(width 0.1)
				(type default)
			)
			(layer "B.Fab")
		)
		(fp_line
			(start 0.32512 -0.175006)
			(end -0.32512 -0.175006)
			(stroke
				(width 0.1)
				(type default)
			)
			(layer "B.Fab")
		)
		(fp_line
			(start -0.32512 0.175006)
			(end 0.32512 0.175006)
			(stroke
				(width 0.1)
				(type default)
			)
			(layer "B.Fab")
		)
		(fp_line
			(start -0.32512 -0.175006)
			(end -0.32512 0.175006)
			(stroke
				(width 0.1)
				(type default)
			)
			(layer "B.Fab")
		)
		(pad "1" smd rect
			(at 0.2667 0)
			(size 0.3048 0.381)
			(layers "B.Cu" "B.Mask" "B.Paste")
			(net "RT_CPU1_P1_SCAN_MODE")
		)
		(pad "2" smd rect
			(at -0.2667 0 180)
			(size 0.3048 0.381)
			(layers "B.Cu" "B.Mask" "B.Paste")
			(net "GND")
		)
	)
	(footprint ""
		(layer "B.Cu")
		(at 216.916 -340.741 -90)
		(property "Reference" "R6752"
			(at 0 0 90)
			(layer "B.SilkS")
			(hide yes)
			(effects
				(font
					(size 1.27 1.27)
				)
				(justify mirror)
			)
		)
		(property "Value" ""
			(at 0 0 90)
			(layer "B.Fab")
			(effects
				(font
					(size 1.27 1.27)
				)
				(justify mirror)
			)
		)
		(duplicate_pad_numbers_are_jumpers no)
		(fp_line
			(start -0.32512 0.175006)
			(end 0.32512 0.175006)
			(stroke
				(width 0.1)
				(type default)
			)
			(layer "B.Fab")
		)
		(fp_line
			(start 0.32512 0.175006)
			(end 0.32512 -0.175006)
			(stroke
				(width 0.1)
				(type default)
			)
			(layer "B.Fab")
		)
		(fp_line
			(start -0.32512 -0.175006)
			(end -0.32512 0.175006)
			(stroke
				(width 0.1)
				(type default)
			)
			(layer "B.Fab")
		)
		(fp_line
			(start 0.32512 -0.175006)
			(end -0.32512 -0.175006)
			(stroke
				(width 0.1)
				(type default)
			)
			(layer "B.Fab")
		)
		(pad "1" smd rect
			(at 0.2667 0 90)
			(size 0.3048 0.381)
			(layers "B.Cu" "B.Mask" "B.Paste")
			(net "P1V8_CPU1_RT_1D")
		)
		(pad "2" smd rect
			(at -0.2667 0 270)
			(size 0.3048 0.381)
			(layers "B.Cu" "B.Mask" "B.Paste")
			(net "SMB_RT_CPU1_P2_R_SDA")
		)
	)
)
